# TIMECARD (Time Appliance Project (Time Card)) — schematic netlist excerpt (pin names and nets, part order shuffled) for the footprints in the layout excerpt that follows; sources: Cadence DE-HDL packaged netlist, KiCad conversion of R4006-B0001-02_R01.brd

R55  RESISTOR  4.7KOHM 1%  pkg SMC_0402R_H016  page 9 : \1\ = PCIE_CONN_PERST_N ; \2\ = SG
R320  RESISTOR  4.7KOHM 1%  pkg SMC_0402R_H016  page 26 : \1\ = XP3R3V_FPGA ; \2\ = RGB_LED_SHUTDOWN_N

(kicad_pcb
	(version 20260206)
	(generator "pcbnew")
	(generator_version "10.0")
	(general
		(thickness 1.6)
		(legacy_teardrops no)
	)
	(paper "A4")
	(title_block
		(title "timecard-production-celestica-r4006 — R4006-B0001-02_R01.brd")
		(comment 1 "Time Appliance Project (Time Card) / footprints 564-565 of 1113")
	)
	(layers
		(0 "F.Cu" signal "TOP")
		(4 "In1.Cu" signal "L02_GND1")
		(6 "In2.Cu" signal "L03_SIG1")
		(8 "In3.Cu" signal "L04_GND2")
		(10 "In4.Cu" signal "L05_VCC1")
		(12 "In5.Cu" signal "L06_VCC2")
		(14 "In6.Cu" signal "L07_GND3")
		(16 "In7.Cu" signal "L08_SIG2")
		(18 "In8.Cu" signal "L09_GND4")
		(2 "B.Cu" signal "BOTTOM")
		(9 "F.Adhes" user "F.Adhesive")
		(11 "B.Adhes" user "B.Adhesive")
		(13 "F.Paste" user "Package Geometry/Pastemask Top")
		(15 "B.Paste" user "Package Geometry/Pastemask Bottom")
		(5 "F.SilkS" user "Ref Des/Silkscreen Top")
		(7 "B.SilkS" user "Ref Des/Silkscreen Bottom")
		(1 "F.Mask" user "Board Geometry/Soldermask Top")
		(3 "B.Mask" user "Board Geometry/Soldermask Bottom")
		(17 "Dwgs.User" user "User.Drawings")
		(19 "Cmts.User" user "User.Comments")
		(21 "Eco1.User" user "User.Eco1")
		(23 "Eco2.User" user "User.Eco2")
		(25 "Edge.Cuts" user "Board Geometry/Outline")
		(27 "Margin" user)
		(31 "F.CrtYd" user "Package Geometry/Place Bound Top")
		(29 "B.CrtYd" user "Package Geometry/Place Bound Bottom")
		(35 "F.Fab" user "Ref Des/Assembly Top")
		(33 "B.Fab" user "Ref Des/Assembly Bottom")
	)
	(footprint ""
		(layer "F.Cu")
		(at 66.4464 -16.637 180)
		(property "Reference" "R55"
			(at -0.9906 1.23063 0)
			(unlocked yes)
			(layer "F.SilkS")
			(effects
				(font
					(size 0.7874 0.5842)
					(thickness 0.1524)
				)
			)
		)
		(property "Value" "VAL*"
			(at 0.02032 2.13233 180)
			(unlocked yes)
			(layer "F.Fab")
			(hide yes)
			(effects
				(font
					(size 0.7874 0.5842)
					(thickness 0.1524)
				)
			)
		)
		(property "Tolerance" "TOL*"
			(at 0.044704 3.05435 180)
			(unlocked yes)
			(layer "Cmts.User")
			(hide yes)
			(effects
				(font
					(size 0.7874 0.5842)
					(thickness 0.1524)
				)
			)
		)
		(property "User Part Number" "PARTNUM*"
			(at 0.02032 4.024884 180)
			(unlocked yes)
			(layer "Cmts.User")
			(hide yes)
			(effects
				(font
					(size 0.7874 0.5842)
					(thickness 0.1524)
				)
			)
		)
		(property "Device Type" "RESISTOR-G155-14701-01,4.7KOHMA"
			(at 0.008382 1.210564 180)
			(unlocked yes)
			(layer "F.Fab")
			(hide yes)
			(effects
				(font
					(size 0.7874 0.5842)
					(thickness 0.1524)
				)
			)
		)
		(duplicate_pad_numbers_are_jumpers no)
		(fp_line
			(start 1.143 0.5588)
			(end 1.143 -0.5588)
			(stroke
				(width 0.1)
				(type default)
			)
			(layer "F.SilkS")
		)
		(fp_line
			(start 1.143 -0.5588)
			(end -1.143 -0.5588)
			(stroke
				(width 0.1)
				(type default)
			)
			(layer "F.SilkS")
		)
		(fp_line
			(start -1.143 0.5588)
			(end 1.143 0.5588)
			(stroke
				(width 0.1)
				(type default)
			)
			(layer "F.SilkS")
		)
		(fp_line
			(start -1.143 -0.5588)
			(end -1.143 0.5588)
			(stroke
				(width 0.1)
				(type default)
			)
			(layer "F.SilkS")
		)
		(fp_rect
			(start 1.143 -0.5588)
			(end -1.143 0.5588)
			(stroke
				(width 0)
				(type default)
			)
			(fill no)
			(layer "F.CrtYd")
		)
		(fp_line
			(start 0.508 0.3048)
			(end 0.508 -0.3048)
			(stroke
				(width 0.1)
				(type default)
			)
			(layer "F.Fab")
		)
		(fp_line
			(start 0.508 -0.3048)
			(end -0.508 -0.3048)
			(stroke
				(width 0.1)
				(type default)
			)
			(layer "F.Fab")
		)
		(fp_line
			(start -0.508 0.3048)
			(end 0.508 0.3048)
			(stroke
				(width 0.1)
				(type default)
			)
			(layer "F.Fab")
		)
		(fp_line
			(start -0.508 -0.3048)
			(end -0.508 0.3048)
			(stroke
				(width 0.1)
				(type default)
			)
			(layer "F.Fab")
		)
		(pad "1" smd rect
			(at -0.5334 0 180)
			(size 0.7112 0.6096)
			(layers "F.Cu" "F.Mask" "F.Paste")
			(net "PCIE_CONN_PERST_N")
		)
		(pad "2" smd rect
			(at 0.5334 0 180)
			(size 0.7112 0.6096)
			(layers "F.Cu" "F.Mask" "F.Paste")
			(net "SG")
		)
		(zone
			(layer "F.Cu")
			(hatch none 0.5)
			(connect_pads
				(clearance 0)
			)
			(min_thickness 0.25)
			(keepout
				(tracks allowed)
				(vias not_allowed)
				(pads allowed)
				(copperpour not_allowed)
				(footprints allowed)
			)
			(placement
				(enabled no)
				(sheetname "")
			)
			(fill
				(thermal_gap 0.5)
				(thermal_bridge_width 0.5)
				(island_removal_mode 0)
			)
			(polygon
				(pts
					(xy 66.3702 -16.3322) (xy 66.5226 -16.3322) (xy 66.5226 -16.9418) (xy 66.3702 -16.9418)
				)
			)
		)
	)
	(footprint ""
		(layer "F.Cu")
		(at 111.125 -98.171 180)
		(property "Reference" "R320"
			(at -3.302 3.38963 0)
			(unlocked yes)
			(layer "F.SilkS")
			(effects
				(font
					(size 0.7874 0.5842)
					(thickness 0.1524)
				)
			)
		)
		(property "Value" "VAL*"
			(at 0.02032 2.13233 180)
			(unlocked yes)
			(layer "F.Fab")
			(hide yes)
			(effects
				(font
					(size 0.7874 0.5842)
					(thickness 0.1524)
				)
			)
		)
		(property "Tolerance" "TOL*"
			(at 0.044704 3.05435 180)
			(unlocked yes)
			(layer "Cmts.User")
			(hide yes)
			(effects
				(font
					(size 0.7874 0.5842)
					(thickness 0.1524)
				)
			)
		)
		(property "User Part Number" "PARTNUM*"
			(at 0.02032 4.024884 180)
			(unlocked yes)
			(layer "Cmts.User")
			(hide yes)
			(effects
				(font
					(size 0.7874 0.5842)
					(thickness 0.1524)
				)
			)
		)
		(property "Device Type" "RESISTOR-G155-14701-01,4.7KOHMA"
			(at 0.008382 1.210564 180)
			(unlocked yes)
			(layer "F.Fab")
			(hide yes)
			(effects
				(font
					(size 0.7874 0.5842)
					(thickness 0.1524)
				)
			)
		)
		(duplicate_pad_numbers_are_jumpers no)
		(fp_line
			(start 1.143 0.5588)
			(end 1.143 -0.5588)
			(stroke
				(width 0.1)
				(type default)
			)
			(layer "F.SilkS")
		)
		(fp_line
			(start 1.143 -0.5588)
			(end -1.143 -0.5588)
			(stroke
				(width 0.1)
				(type default)
			)
			(layer "F.SilkS")
		)
		(fp_line
			(start -1.143 0.5588)
			(end 1.143 0.5588)
			(stroke
				(width 0.1)
				(type default)
			)
			(layer "F.SilkS")
		)
		(fp_line
			(start -1.143 -0.5588)
			(end -1.143 0.5588)
			(stroke
				(width 0.1)
				(type default)
			)
			(layer "F.SilkS")
		)
		(fp_poly
			(pts
				(xy -1.143 0.5588) (xy 1.143 0.5588) (xy 1.143 -0.5588) (xy -1.143 -0.5588)
			)
			(stroke
				(width 0)
				(type default)
			)
			(fill no)
			(layer "F.CrtYd")
		)
		(fp_line
			(start 0.508 0.3048)
			(end 0.508 -0.3048)
			(stroke
				(width 0.1)
				(type default)
			)
			(layer "F.Fab")
		)
		(fp_line
			(start 0.508 -0.3048)
			(end -0.508 -0.3048)
			(stroke
				(width 0.1)
				(type default)
			)
			(layer "F.Fab")
		)
		(fp_line
			(start -0.508 0.3048)
			(end 0.508 0.3048)
			(stroke
				(width 0.1)
				(type default)
			)
			(layer "F.Fab")
		)
		(fp_line
			(start -0.508 -0.3048)
			(end -0.508 0.3048)
			(stroke
				(width 0.1)
				(type default)
			)
			(layer "F.Fab")
		)
		(pad "1" smd rect
			(at -0.5334 0 180)
			(size 0.7112 0.6096)
			(layers "F.Cu" "F.Mask" "F.Paste")
			(net "XP3R3V_FPGA")
		)
		(pad "2" smd rect
			(at 0.5334 0 180)
			(size 0.7112 0.6096)
			(layers "F.Cu" "F.Mask" "F.Paste")
			(net "RGB_LED_SHUTDOWN_N")
		)
		(zone
			(layer "F.Cu")
			(hatch none 0.5)
			(connect_pads
				(clearance 0)
			)
			(min_thickness 0.25)
			(keepout
				(tracks allowed)
				(vias not_allowed)
				(pads allowed)
				(copperpour not_allowed)
				(footprints allowed)
			)
			(placement
				(enabled no)
				(sheetname "")
			)
			(fill
				(thermal_gap 0.5)
				(thermal_bridge_width 0.5)
				(island_removal_mode 0)
			)
			(polygon
				(pts
					(xy 111.2012 -98.4758) (xy 111.0488 -98.4758) (xy 111.0488 -97.8662) (xy 111.2012 -97.8662)
				)
			)
		)
		(zone
			(layer "F.Cu")
			(hatch none 0.5)
			(connect_pads
				(clearance 0)
			)
			(min_thickness 0.25)
			(keepout
				(tracks not_allowed)
				(vias allowed)
				(pads allowed)
				(copperpour not_allowed)
				(footprints allowed)
			)
			(placement
				(enabled no)
				(sheetname "")
			)
			(fill
				(thermal_gap 0.5)
				(thermal_bridge_width 0.5)
				(island_removal_mode 0)
			)
			(polygon
				(pts
					(xy 111.2012 -98.4758) (xy 111.0488 -98.4758) (xy 111.0488 -97.8662) (xy 111.2012 -97.8662)
				)
			)
		)
	)
)
